# T6G (Grand Teton) — schematic netlist excerpt (pin names and nets, part order shuffled) for the footprints in the layout excerpt that follows; sources: Cadence DE-HDL packaged netlist, KiCad conversion of 04192023_DAF0TMB3IC0_F0TG_MB_C_brd_V02_OCP.brd

R6166  Q_RES  1K 1% EMPTY  pkg 0402LF  page 112 : A = FM_P2E_BUF2_EQB0 ; B = GND
C1973  Q_CAP  0.1UF 25V 10% X7R  pkg 0402  page 126 : A = GPU_BASE_HMC_READY_ISO ; B = GND

(kicad_pcb
	(version 20260206)
	(generator "pcbnew")
	(generator_version "10.0")
	(general
		(thickness 1.6)
		(legacy_teardrops no)
	)
	(paper "A4")
	(title_block
		(title "04192023_DAF0TMB3IC0_F0TG_MB_C_brd_V02_OCP.brd")
		(comment 1 "Grand Teton / footprints 839-840 of 8354")
	)
	(layers
		(0 "F.Cu" signal "TOP")
		(4 "In1.Cu" signal "GND")
		(6 "In2.Cu" signal "IN1")
		(8 "In3.Cu" signal "GND1")
		(10 "In4.Cu" signal "IN2")
		(12 "In5.Cu" signal "GND2")
		(14 "In6.Cu" signal "IN3")
		(16 "In7.Cu" signal "GND3")
		(18 "In8.Cu" signal "VCC")
		(20 "In9.Cu" signal "VCC1")
		(22 "In10.Cu" signal "GND4")
		(24 "In11.Cu" signal "IN4")
		(26 "In12.Cu" signal "GND5")
		(28 "In13.Cu" signal "IN5")
		(30 "In14.Cu" signal "GND6")
		(32 "In15.Cu" signal "IN6")
		(34 "In16.Cu" signal "GND7")
		(2 "B.Cu" signal "BOTTOM")
		(9 "F.Adhes" user "F.Adhesive")
		(11 "B.Adhes" user "B.Adhesive")
		(13 "F.Paste" user "Package Geometry/Pastemask Top")
		(15 "B.Paste" user "Package Geometry/Pastemask Bottom")
		(5 "F.SilkS" user "Ref Des/Silkscreen Top")
		(7 "B.SilkS" user "Ref Des/Silkscreen Bottom")
		(1 "F.Mask" user "Board Geometry/Soldermask Top")
		(3 "B.Mask" user "Board Geometry/Soldermask Bottom")
		(17 "Dwgs.User" user "User.Drawings")
		(19 "Cmts.User" user "User.Comments")
		(21 "Eco1.User" user "User.Eco1")
		(23 "Eco2.User" user "User.Eco2")
		(25 "Edge.Cuts" user "Board Geometry/Outline")
		(27 "Margin" user)
		(31 "F.CrtYd" user "Package Geometry/Place Bound Top")
		(29 "B.CrtYd" user "Package Geometry/Place Bound Bottom")
		(35 "F.Fab" user "Ref Des/Assembly Top")
		(33 "B.Fab" user "Ref Des/Assembly Bottom")
	)
	(footprint ""
		(layer "F.Cu")
		(at 165.2016 -436.153052)
		(property "Reference" "C1973"
			(at 0 0 0)
			(layer "F.SilkS")
			(hide yes)
			(effects
				(font
					(size 1.27 1.27)
				)
			)
		)
		(property "Value" ""
			(at 0 0 0)
			(layer "F.Fab")
			(effects
				(font
					(size 1.27 1.27)
				)
			)
		)
		(duplicate_pad_numbers_are_jumpers no)
		(fp_line
			(start -0.7874 -0.4064)
			(end 0.7874 -0.4064)
			(stroke
				(width 0.1524)
				(type default)
			)
			(layer "F.SilkS")
		)
		(fp_line
			(start -0.7874 0.4064)
			(end -0.7874 -0.4064)
			(stroke
				(width 0.1524)
				(type default)
			)
			(layer "F.SilkS")
		)
		(fp_line
			(start 0.7874 -0.4064)
			(end 0.7874 0.4064)
			(stroke
				(width 0.1524)
				(type default)
			)
			(layer "F.SilkS")
		)
		(fp_line
			(start 0.7874 0.4064)
			(end -0.7874 0.4064)
			(stroke
				(width 0.1524)
				(type default)
			)
			(layer "F.SilkS")
		)
		(fp_line
			(start -0.67945 -0.305054)
			(end -0.12065 -0.305054)
			(stroke
				(width 0.1)
				(type default)
			)
			(layer "F.Fab")
		)
		(fp_line
			(start -0.67945 0.3048)
			(end -0.67945 -0.305054)
			(stroke
				(width 0.1)
				(type default)
			)
			(layer "F.Fab")
		)
		(fp_line
			(start -0.12065 -0.305054)
			(end -0.12065 -0.2794)
			(stroke
				(width 0.1)
				(type default)
			)
			(layer "F.Fab")
		)
		(fp_line
			(start -0.12065 -0.2794)
			(end 0.12065 -0.2794)
			(stroke
				(width 0.1)
				(type default)
			)
			(layer "F.Fab")
		)
		(fp_line
			(start -0.12065 0.2794)
			(end -0.12065 0.3048)
			(stroke
				(width 0.1)
				(type default)
			)
			(layer "F.Fab")
		)
		(fp_line
			(start -0.12065 0.3048)
			(end -0.67945 0.3048)
			(stroke
				(width 0.1)
				(type default)
			)
			(layer "F.Fab")
		)
		(fp_line
			(start 0.120396 0.2794)
			(end -0.12065 0.2794)
			(stroke
				(width 0.1)
				(type default)
			)
			(layer "F.Fab")
		)
		(fp_line
			(start 0.120396 0.3048)
			(end 0.120396 0.2794)
			(stroke
				(width 0.1)
				(type default)
			)
			(layer "F.Fab")
		)
		(fp_line
			(start 0.12065 -0.3048)
			(end 0.67945 -0.3048)
			(stroke
				(width 0.1)
				(type default)
			)
			(layer "F.Fab")
		)
		(fp_line
			(start 0.12065 -0.2794)
			(end 0.12065 -0.3048)
			(stroke
				(width 0.1)
				(type default)
			)
			(layer "F.Fab")
		)
		(fp_line
			(start 0.67945 -0.3048)
			(end 0.67945 0.3048)
			(stroke
				(width 0.1)
				(type default)
			)
			(layer "F.Fab")
		)
		(fp_line
			(start 0.67945 0.3048)
			(end 0.120396 0.3048)
			(stroke
				(width 0.1)
				(type default)
			)
			(layer "F.Fab")
		)
		(pad "1" smd circle
			(at -0.40005 0)
			(size 0 0)
			(layers "F.Cu" "F.Mask" "F.Paste")
			(net "GPU_BASE_HMC_READY_ISO")
		)
		(pad "2" smd circle
			(at 0.40005 0)
			(size 0 0)
			(layers "F.Cu" "F.Mask" "F.Paste")
			(net "GND")
		)
	)
	(footprint ""
		(layer "F.Cu")
		(at 21.876258 -427.580298 90)
		(property "Reference" "R6166"
			(at 0 0 90)
			(layer "F.SilkS")
			(hide yes)
			(effects
				(font
					(size 1.27 1.27)
				)
			)
		)
		(property "Value" ""
			(at 0 0 90)
			(layer "F.Fab")
			(effects
				(font
					(size 1.27 1.27)
				)
			)
		)
		(duplicate_pad_numbers_are_jumpers no)
		(fp_line
			(start 0.7874 -0.4064)
			(end 0.7874 0.4064)
			(stroke
				(width 0.1524)
				(type default)
			)
			(layer "F.SilkS")
		)
		(fp_line
			(start -0.7874 -0.4064)
			(end 0.7874 -0.4064)
			(stroke
				(width 0.1524)
				(type default)
			)
			(layer "F.SilkS")
		)
		(fp_line
			(start 0.7874 0.4064)
			(end -0.7874 0.4064)
			(stroke
				(width 0.1524)
				(type default)
			)
			(layer "F.SilkS")
		)
		(fp_line
			(start -0.7874 0.4064)
			(end -0.7874 -0.4064)
			(stroke
				(width 0.1524)
				(type default)
			)
			(layer "F.SilkS")
		)
		(fp_line
			(start -0.12065 -0.305054)
			(end -0.12065 -0.2794)
			(stroke
				(width 0.1)
				(type default)
			)
			(layer "F.Fab")
		)
		(fp_line
			(start -0.67945 -0.305054)
			(end -0.12065 -0.305054)
			(stroke
				(width 0.1)
				(type default)
			)
			(layer "F.Fab")
		)
		(fp_line
			(start 0.67945 -0.3048)
			(end 0.67945 0.3048)
			(stroke
				(width 0.1)
				(type default)
			)
			(layer "F.Fab")
		)
		(fp_line
			(start 0.12065 -0.3048)
			(end 0.67945 -0.3048)
			(stroke
				(width 0.1)
				(type default)
			)
			(layer "F.Fab")
		)
		(fp_line
			(start 0.12065 -0.2794)
			(end 0.12065 -0.3048)
			(stroke
				(width 0.1)
				(type default)
			)
			(layer "F.Fab")
		)
		(fp_line
			(start -0.12065 -0.2794)
			(end 0.12065 -0.2794)
			(stroke
				(width 0.1)
				(type default)
			)
			(layer "F.Fab")
		)
		(fp_line
			(start 0.120396 0.2794)
			(end -0.12065 0.2794)
			(stroke
				(width 0.1)
				(type default)
			)
			(layer "F.Fab")
		)
		(fp_line
			(start -0.12065 0.2794)
			(end -0.12065 0.3048)
			(stroke
				(width 0.1)
				(type default)
			)
			(layer "F.Fab")
		)
		(fp_line
			(start 0.67945 0.3048)
			(end 0.120396 0.3048)
			(stroke
				(width 0.1)
				(type default)
			)
			(layer "F.Fab")
		)
		(fp_line
			(start 0.120396 0.3048)
			(end 0.120396 0.2794)
			(stroke
				(width 0.1)
				(type default)
			)
			(layer "F.Fab")
		)
		(fp_line
			(start -0.12065 0.3048)
			(end -0.67945 0.3048)
			(stroke
				(width 0.1)
				(type default)
			)
			(layer "F.Fab")
		)
		(fp_line
			(start -0.67945 0.3048)
			(end -0.67945 -0.305054)
			(stroke
				(width 0.1)
				(type default)
			)
			(layer "F.Fab")
		)
		(pad "1" smd circle
			(at -0.40005 0 90)
			(size 0 0)
			(layers "F.Cu" "F.Mask" "F.Paste")
			(net "FM_P2E_BUF2_EQB0")
		)
		(pad "2" smd circle
			(at 0.40005 0 90)
			(size 0 0)
			(layers "F.Cu" "F.Mask" "F.Paste")
			(net "GND")
		)
	)
)
